(kicad_pcb
	(version 20260206)
	(generator "pcbnew")
	(generator_version "10.0")
	(general
		(thickness 1.6)
		(legacy_teardrops no)
	)
	(paper "A4")
	(title_block
		(title "12092022_DA0F0TMDCD0_F0T_Management_Board_D_brd_V3_OCP.brd")
		(comment 1 "Grand Teton / footprints 407-412 of 1440")
	)
	(layers
		(0 "F.Cu" signal "TOP")
		(4 "In1.Cu" signal "GND")
		(6 "In2.Cu" signal "IN1")
		(8 "In3.Cu" signal "GND1")
		(10 "In4.Cu" signal "IN2")
		(12 "In5.Cu" signal "VCC")
		(14 "In6.Cu" signal "VCC1")
		(16 "In7.Cu" signal "IN3")
		(18 "In8.Cu" signal "GND2")
		(20 "In9.Cu" signal "IN4")
		(22 "In10.Cu" signal "GND3")
		(2 "B.Cu" signal "BOTTOM")
		(9 "F.Adhes" user "F.Adhesive")
		(11 "B.Adhes" user "B.Adhesive")
		(13 "F.Paste" user "Package Geometry/Pastemask Top")
		(15 "B.Paste" user "Package Geometry/Pastemask Bottom")
		(5 "F.SilkS" user "Ref Des/Silkscreen Top")
		(7 "B.SilkS" user "Ref Des/Silkscreen Bottom")
		(1 "F.Mask" user "Board Geometry/Soldermask Top")
		(3 "B.Mask" user "Board Geometry/Soldermask Bottom")
		(17 "Dwgs.User" user "User.Drawings")
		(19 "Cmts.User" user "User.Comments")
		(21 "Eco1.User" user "User.Eco1")
		(23 "Eco2.User" user "User.Eco2")
		(25 "Edge.Cuts" user "Board Geometry/Outline")
		(27 "Margin" user)
		(31 "F.CrtYd" user "Package Geometry/Place Bound Top")
		(29 "B.CrtYd" user "Package Geometry/Place Bound Bottom")
		(35 "F.Fab" user "Ref Des/Assembly Top")
		(33 "B.Fab" user "Ref Des/Assembly Bottom")
	)
	(footprint ""
		(layer "F.Cu")
		(at 33.782 -68.453 90)
		(property "Reference" "R11"
			(at 0 0 90)
			(layer "F.SilkS")
			(hide yes)
			(effects
				(font
					(size 1.27 1.27)
				)
			)
		)
		(property "Value" ""
			(at 0 0 90)
			(layer "F.Fab")
			(effects
				(font
					(size 1.27 1.27)
				)
			)
		)
		(duplicate_pad_numbers_are_jumpers no)
		(fp_line
			(start 0.7874 -0.4064)
			(end 0.7874 0.4064)
			(stroke
				(width 0.1524)
				(type default)
			)
			(layer "F.SilkS")
		)
		(fp_line
			(start -0.7874 -0.4064)
			(end 0.7874 -0.4064)
			(stroke
				(width 0.1524)
				(type default)
			)
			(layer "F.SilkS")
		)
		(fp_line
			(start 0.7874 0.4064)
			(end -0.7874 0.4064)
			(stroke
				(width 0.1524)
				(type default)
			)
			(layer "F.SilkS")
		)
		(fp_line
			(start -0.7874 0.4064)
			(end -0.7874 -0.4064)
			(stroke
				(width 0.1524)
				(type default)
			)
			(layer "F.SilkS")
		)
		(fp_line
			(start -0.12065 -0.305054)
			(end -0.12065 -0.2794)
			(stroke
				(width 0.1)
				(type default)
			)
			(layer "F.Fab")
		)
		(fp_line
			(start -0.67945 -0.305054)
			(end -0.12065 -0.305054)
			(stroke
				(width 0.1)
				(type default)
			)
			(layer "F.Fab")
		)
		(fp_line
			(start 0.67945 -0.3048)
			(end 0.67945 0.3048)
			(stroke
				(width 0.1)
				(type default)
			)
			(layer "F.Fab")
		)
		(fp_line
			(start 0.12065 -0.3048)
			(end 0.67945 -0.3048)
			(stroke
				(width 0.1)
				(type default)
			)
			(layer "F.Fab")
		)
		(fp_line
			(start 0.12065 -0.2794)
			(end 0.12065 -0.3048)
			(stroke
				(width 0.1)
				(type default)
			)
			(layer "F.Fab")
		)
		(fp_line
			(start -0.12065 -0.2794)
			(end 0.12065 -0.2794)
			(stroke
				(width 0.1)
				(type default)
			)
			(layer "F.Fab")
		)
		(fp_line
			(start 0.120396 0.2794)
			(end -0.12065 0.2794)
			(stroke
				(width 0.1)
				(type default)
			)
			(layer "F.Fab")
		)
		(fp_line
			(start -0.12065 0.2794)
			(end -0.12065 0.3048)
			(stroke
				(width 0.1)
				(type default)
			)
			(layer "F.Fab")
		)
		(fp_line
			(start 0.67945 0.3048)
			(end 0.120396 0.3048)
			(stroke
				(width 0.1)
				(type default)
			)
			(layer "F.Fab")
		)
		(fp_line
			(start 0.120396 0.3048)
			(end 0.120396 0.2794)
			(stroke
				(width 0.1)
				(type default)
			)
			(layer "F.Fab")
		)
		(fp_line
			(start -0.12065 0.3048)
			(end -0.67945 0.3048)
			(stroke
				(width 0.1)
				(type default)
			)
			(layer "F.Fab")
		)
		(fp_line
			(start -0.67945 0.3048)
			(end -0.67945 -0.305054)
			(stroke
				(width 0.1)
				(type default)
			)
			(layer "F.Fab")
		)
		(pad "1" smd circle
			(at -0.40005 0 90)
			(size 0 0)
			(layers "F.Cu" "F.Mask" "F.Paste")
			(net "P3V3_AUX")
		)
		(pad "2" smd circle
			(at 0.40005 0 90)
			(size 0 0)
			(layers "F.Cu" "F.Mask" "F.Paste")
			(net "BMC_EMMC_RST_N")
		)
	)
	(footprint ""
		(layer "F.Cu")
		(at 12.875006 -25.146 180)
		(property "Reference" "J6"
			(at 4.6228 3.38963 0)
			(unlocked yes)
			(layer "F.SilkS")
			(effects
				(font
					(size 0.7874 0.5842)
					(thickness 0.1524)
				)
				(justify left)
			)
		)
		(property "Value" ""
			(at 0 0 180)
			(layer "F.Fab")
			(effects
				(font
					(size 1.27 1.27)
				)
			)
		)
		(duplicate_pad_numbers_are_jumpers no)
		(fp_line
			(start 1.249934 3.860038)
			(end 1.249934 3.1877)
			(stroke
				(width 0.1524)
				(type default)
			)
			(layer "F.SilkS")
		)
		(fp_line
			(start 1.249934 1.8923)
			(end 1.249934 -1.8923)
			(stroke
				(width 0.1524)
				(type default)
			)
			(layer "F.SilkS")
		)
		(fp_line
			(start 1.249934 -3.1877)
			(end 1.249934 -3.860038)
			(stroke
				(width 0.1524)
				(type default)
			)
			(layer "F.SilkS")
		)
		(fp_line
			(start 1.249934 -3.860038)
			(end -1.249934 -3.860038)
			(stroke
				(width 0.1524)
				(type default)
			)
			(layer "F.SilkS")
		)
		(fp_line
			(start -1.249934 3.860038)
			(end 1.249934 3.860038)
			(stroke
				(width 0.1524)
				(type default)
			)
			(layer "F.SilkS")
		)
		(fp_line
			(start -1.249934 0.6477)
			(end -1.249934 3.860038)
			(stroke
				(width 0.1524)
				(type default)
			)
			(layer "F.SilkS")
		)
		(fp_line
			(start -1.249934 -3.860038)
			(end -1.249934 -0.6477)
			(stroke
				(width 0.1524)
				(type default)
			)
			(layer "F.SilkS")
		)
		(fp_poly
			(pts
				(xy 2.413 -5.334) (xy 1.397 -5.334) (xy 1.905 -4.318)
			)
			(stroke
				(width 0)
				(type default)
			)
			(fill yes)
			(layer "F.SilkS")
		)
		(fp_line
			(start 1.249934 3.860038)
			(end 1.249934 -3.860038)
			(stroke
				(width 0.1)
				(type default)
			)
			(layer "F.Fab")
		)
		(fp_line
			(start 1.249934 -3.860038)
			(end -1.249934 -3.860038)
			(stroke
				(width 0.1)
				(type default)
			)
			(layer "F.Fab")
		)
		(fp_line
			(start -1.249934 3.860038)
			(end 1.249934 3.860038)
			(stroke
				(width 0.1)
				(type default)
			)
			(layer "F.Fab")
		)
		(fp_line
			(start -1.249934 -3.860038)
			(end -1.249934 3.860038)
			(stroke
				(width 0.1)
				(type default)
			)
			(layer "F.Fab")
		)
		(fp_poly
			(pts
				(xy 4.281678 -2.032) (xy 4.281678 -3.048) (xy 3.265678 -2.54)
			)
			(stroke
				(width 0)
				(type default)
			)
			(fill yes)
			(layer "F.Fab")
		)
		(pad "1" smd rect
			(at 1.374902 -2.54 90)
			(size 1.016 2.7686)
			(layers "F.Cu" "F.Mask" "F.Paste")
			(net "UART_BMC_5_TXD_BUF_R")
		)
		(pad "2" smd rect
			(at -1.374902 0 90)
			(size 1.016 2.7686)
			(layers "F.Cu" "F.Mask" "F.Paste")
			(net "GND")
		)
		(pad "3" smd rect
			(at 1.374902 2.54 90)
			(size 1.016 2.7686)
			(layers "F.Cu" "F.Mask" "F.Paste")
			(net "UART_BMC_5_RXD_BUF")
		)
	)
	(footprint ""
		(layer "F.Cu")
		(at 19.431 -83.72602 -90)
		(property "Reference" "R297"
			(at 0 0 270)
			(layer "F.SilkS")
			(hide yes)
			(effects
				(font
					(size 1.27 1.27)
				)
			)
		)
		(property "Value" ""
			(at 0 0 270)
			(layer "F.Fab")
			(effects
				(font
					(size 1.27 1.27)
				)
			)
		)
		(duplicate_pad_numbers_are_jumpers no)
		(fp_line
			(start -0.7874 0.4064)
			(end -0.7874 -0.4064)
			(stroke
				(width 0.1524)
				(type default)
			)
			(layer "F.SilkS")
		)
		(fp_line
			(start 0.7874 0.4064)
			(end -0.7874 0.4064)
			(stroke
				(width 0.1524)
				(type default)
			)
			(layer "F.SilkS")
		)
		(fp_line
			(start -0.7874 -0.4064)
			(end 0.7874 -0.4064)
			(stroke
				(width 0.1524)
				(type default)
			)
			(layer "F.SilkS")
		)
		(fp_line
			(start 0.7874 -0.4064)
			(end 0.7874 0.4064)
			(stroke
				(width 0.1524)
				(type default)
			)
			(layer "F.SilkS")
		)
		(fp_line
			(start -0.67945 0.3048)
			(end -0.67945 -0.305054)
			(stroke
				(width 0.1)
				(type default)
			)
			(layer "F.Fab")
		)
		(fp_line
			(start -0.12065 0.3048)
			(end -0.67945 0.3048)
			(stroke
				(width 0.1)
				(type default)
			)
			(layer "F.Fab")
		)
		(fp_line
			(start 0.120396 0.3048)
			(end 0.120396 0.2794)
			(stroke
				(width 0.1)
				(type default)
			)
			(layer "F.Fab")
		)
		(fp_line
			(start 0.67945 0.3048)
			(end 0.120396 0.3048)
			(stroke
				(width 0.1)
				(type default)
			)
			(layer "F.Fab")
		)
		(fp_line
			(start -0.12065 0.2794)
			(end -0.12065 0.3048)
			(stroke
				(width 0.1)
				(type default)
			)
			(layer "F.Fab")
		)
		(fp_line
			(start 0.120396 0.2794)
			(end -0.12065 0.2794)
			(stroke
				(width 0.1)
				(type default)
			)
			(layer "F.Fab")
		)
		(fp_line
			(start -0.12065 -0.2794)
			(end 0.12065 -0.2794)
			(stroke
				(width 0.1)
				(type default)
			)
			(layer "F.Fab")
		)
		(fp_line
			(start 0.12065 -0.2794)
			(end 0.12065 -0.3048)
			(stroke
				(width 0.1)
				(type default)
			)
			(layer "F.Fab")
		)
		(fp_line
			(start 0.12065 -0.3048)
			(end 0.67945 -0.3048)
			(stroke
				(width 0.1)
				(type default)
			)
			(layer "F.Fab")
		)
		(fp_line
			(start 0.67945 -0.3048)
			(end 0.67945 0.3048)
			(stroke
				(width 0.1)
				(type default)
			)
			(layer "F.Fab")
		)
		(fp_line
			(start -0.67945 -0.305054)
			(end -0.12065 -0.305054)
			(stroke
				(width 0.1)
				(type default)
			)
			(layer "F.Fab")
		)
		(fp_line
			(start -0.12065 -0.305054)
			(end -0.12065 -0.2794)
			(stroke
				(width 0.1)
				(type default)
			)
			(layer "F.Fab")
		)
		(pad "1" smd circle
			(at -0.40005 0 270)
			(size 0 0)
			(layers "F.Cu" "F.Mask" "F.Paste")
			(net "PU_PT20D")
		)
		(pad "2" smd circle
			(at 0.40005 0 270)
			(size 0 0)
			(layers "F.Cu" "F.Mask" "F.Paste")
			(net "VCCIO2")
		)
	)
	(footprint ""
		(layer "F.Cu")
		(at 84.201 -97.917)
		(property "Reference" "R100"
			(at 0 0 0)
			(layer "F.SilkS")
			(hide yes)
			(effects
				(font
					(size 1.27 1.27)
				)
			)
		)
		(property "Value" ""
			(at 0 0 0)
			(layer "F.Fab")
			(effects
				(font
					(size 1.27 1.27)
				)
			)
		)
		(duplicate_pad_numbers_are_jumpers no)
		(fp_line
			(start -0.7874 -0.4064)
			(end 0.7874 -0.4064)
			(stroke
				(width 0.1524)
				(type default)
			)
			(layer "F.SilkS")
		)
		(fp_line
			(start -0.7874 0.4064)
			(end -0.7874 -0.4064)
			(stroke
				(width 0.1524)
				(type default)
			)
			(layer "F.SilkS")
		)
		(fp_line
			(start 0.7874 -0.4064)
			(end 0.7874 0.4064)
			(stroke
				(width 0.1524)
				(type default)
			)
			(layer "F.SilkS")
		)
		(fp_line
			(start 0.7874 0.4064)
			(end -0.7874 0.4064)
			(stroke
				(width 0.1524)
				(type default)
			)
			(layer "F.SilkS")
		)
		(fp_line
			(start -0.67945 -0.305054)
			(end -0.12065 -0.305054)
			(stroke
				(width 0.1)
				(type default)
			)
			(layer "F.Fab")
		)
		(fp_line
			(start -0.67945 0.3048)
			(end -0.67945 -0.305054)
			(stroke
				(width 0.1)
				(type default)
			)
			(layer "F.Fab")
		)
		(fp_line
			(start -0.12065 -0.305054)
			(end -0.12065 -0.2794)
			(stroke
				(width 0.1)
				(type default)
			)
			(layer "F.Fab")
		)
		(fp_line
			(start -0.12065 -0.2794)
			(end 0.12065 -0.2794)
			(stroke
				(width 0.1)
				(type default)
			)
			(layer "F.Fab")
		)
		(fp_line
			(start -0.12065 0.2794)
			(end -0.12065 0.3048)
			(stroke
				(width 0.1)
				(type default)
			)
			(layer "F.Fab")
		)
		(fp_line
			(start -0.12065 0.3048)
			(end -0.67945 0.3048)
			(stroke
				(width 0.1)
				(type default)
			)
			(layer "F.Fab")
		)
		(fp_line
			(start 0.120396 0.2794)
			(end -0.12065 0.2794)
			(stroke
				(width 0.1)
				(type default)
			)
			(layer "F.Fab")
		)
		(fp_line
			(start 0.120396 0.3048)
			(end 0.120396 0.2794)
			(stroke
				(width 0.1)
				(type default)
			)
			(layer "F.Fab")
		)
		(fp_line
			(start 0.12065 -0.3048)
			(end 0.67945 -0.3048)
			(stroke
				(width 0.1)
				(type default)
			)
			(layer "F.Fab")
		)
		(fp_line
			(start 0.12065 -0.2794)
			(end 0.12065 -0.3048)
			(stroke
				(width 0.1)
				(type default)
			)
			(layer "F.Fab")
		)
		(fp_line
			(start 0.67945 -0.3048)
			(end 0.67945 0.3048)
			(stroke
				(width 0.1)
				(type default)
			)
			(layer "F.Fab")
		)
		(fp_line
			(start 0.67945 0.3048)
			(end 0.120396 0.3048)
			(stroke
				(width 0.1)
				(type default)
			)
			(layer "F.Fab")
		)
		(pad "1" smd circle
			(at -0.40005 0)
			(size 0 0)
			(layers "F.Cu" "F.Mask" "F.Paste")
			(net "SPI_BMC_TPM_CS2_N_R")
		)
		(pad "2" smd circle
			(at 0.40005 0)
			(size 0 0)
			(layers "F.Cu" "F.Mask" "F.Paste")
			(net "SPI_BMC_TPM_CS2_R_N")
		)
	)
	(footprint ""
		(layer "F.Cu")
		(at 10.287 -59.055 90)
		(property "Reference" "C262"
			(at 0 0 90)
			(layer "F.SilkS")
			(hide yes)
			(effects
				(font
					(size 1.27 1.27)
				)
			)
		)
		(property "Value" ""
			(at 0 0 90)
			(layer "F.Fab")
			(effects
				(font
					(size 1.27 1.27)
				)
			)
		)
		(duplicate_pad_numbers_are_jumpers no)
		(fp_line
			(start 0.7874 -0.4064)
			(end 0.7874 0.4064)
			(stroke
				(width 0.1524)
				(type default)
			)
			(layer "F.SilkS")
		)
		(fp_line
			(start -0.7874 -0.4064)
			(end 0.7874 -0.4064)
			(stroke
				(width 0.1524)
				(type default)
			)
			(layer "F.SilkS")
		)
		(fp_line
			(start 0.7874 0.4064)
			(end -0.7874 0.4064)
			(stroke
				(width 0.1524)
				(type default)
			)
			(layer "F.SilkS")
		)
		(fp_line
			(start -0.7874 0.4064)
			(end -0.7874 -0.4064)
			(stroke
				(width 0.1524)
				(type default)
			)
			(layer "F.SilkS")
		)
		(fp_line
			(start -0.12065 -0.305054)
			(end -0.12065 -0.2794)
			(stroke
				(width 0.1)
				(type default)
			)
			(layer "F.Fab")
		)
		(fp_line
			(start -0.67945 -0.305054)
			(end -0.12065 -0.305054)
			(stroke
				(width 0.1)
				(type default)
			)
			(layer "F.Fab")
		)
		(fp_line
			(start 0.67945 -0.3048)
			(end 0.67945 0.3048)
			(stroke
				(width 0.1)
				(type default)
			)
			(layer "F.Fab")
		)
		(fp_line
			(start 0.12065 -0.3048)
			(end 0.67945 -0.3048)
			(stroke
				(width 0.1)
				(type default)
			)
			(layer "F.Fab")
		)
		(fp_line
			(start 0.12065 -0.2794)
			(end 0.12065 -0.3048)
			(stroke
				(width 0.1)
				(type default)
			)
			(layer "F.Fab")
		)
		(fp_line
			(start -0.12065 -0.2794)
			(end 0.12065 -0.2794)
			(stroke
				(width 0.1)
				(type default)
			)
			(layer "F.Fab")
		)
		(fp_line
			(start 0.120396 0.2794)
			(end -0.12065 0.2794)
			(stroke
				(width 0.1)
				(type default)
			)
			(layer "F.Fab")
		)
		(fp_line
			(start -0.12065 0.2794)
			(end -0.12065 0.3048)
			(stroke
				(width 0.1)
				(type default)
			)
			(layer "F.Fab")
		)
		(fp_line
			(start 0.67945 0.3048)
			(end 0.120396 0.3048)
			(stroke
				(width 0.1)
				(type default)
			)
			(layer "F.Fab")
		)
		(fp_line
			(start 0.120396 0.3048)
			(end 0.120396 0.2794)
			(stroke
				(width 0.1)
				(type default)
			)
			(layer "F.Fab")
		)
		(fp_line
			(start -0.12065 0.3048)
			(end -0.67945 0.3048)
			(stroke
				(width 0.1)
				(type default)
			)
			(layer "F.Fab")
		)
		(fp_line
			(start -0.67945 0.3048)
			(end -0.67945 -0.305054)
			(stroke
				(width 0.1)
				(type default)
			)
			(layer "F.Fab")
		)
		(pad "1" smd circle
			(at -0.40005 0 90)
			(size 0 0)
			(layers "F.Cu" "F.Mask" "F.Paste")
			(net "P12V_AUX")
		)
		(pad "2" smd circle
			(at 0.40005 0 90)
			(size 0 0)
			(layers "F.Cu" "F.Mask" "F.Paste")
			(net "GND")
		)
	)
	(footprint ""
		(layer "F.Cu")
		(at 84.201 -92.202)
		(property "Reference" "R109"
			(at 0 0 0)
			(layer "F.SilkS")
			(hide yes)
			(effects
				(font
					(size 1.27 1.27)
				)
			)
		)
		(property "Value" ""
			(at 0 0 0)
			(layer "F.Fab")
			(effects
				(font
					(size 1.27 1.27)
				)
			)
		)
		(duplicate_pad_numbers_are_jumpers no)
		(fp_line
			(start -0.7874 -0.4064)
			(end 0.7874 -0.4064)
			(stroke
				(width 0.1524)
				(type default)
			)
			(layer "F.SilkS")
		)
		(fp_line
			(start -0.7874 0.4064)
			(end -0.7874 -0.4064)
			(stroke
				(width 0.1524)
				(type default)
			)
			(layer "F.SilkS")
		)
		(fp_line
			(start 0.7874 -0.4064)
			(end 0.7874 0.4064)
			(stroke
				(width 0.1524)
				(type default)
			)
			(layer "F.SilkS")
		)
		(fp_line
			(start 0.7874 0.4064)
			(end -0.7874 0.4064)
			(stroke
				(width 0.1524)
				(type default)
			)
			(layer "F.SilkS")
		)
		(fp_line
			(start -0.67945 -0.305054)
			(end -0.12065 -0.305054)
			(stroke
				(width 0.1)
				(type default)
			)
			(layer "F.Fab")
		)
		(fp_line
			(start -0.67945 0.3048)
			(end -0.67945 -0.305054)
			(stroke
				(width 0.1)
				(type default)
			)
			(layer "F.Fab")
		)
		(fp_line
			(start -0.12065 -0.305054)
			(end -0.12065 -0.2794)
			(stroke
				(width 0.1)
				(type default)
			)
			(layer "F.Fab")
		)
		(fp_line
			(start -0.12065 -0.2794)
			(end 0.12065 -0.2794)
			(stroke
				(width 0.1)
				(type default)
			)
			(layer "F.Fab")
		)
		(fp_line
			(start -0.12065 0.2794)
			(end -0.12065 0.3048)
			(stroke
				(width 0.1)
				(type default)
			)
			(layer "F.Fab")
		)
		(fp_line
			(start -0.12065 0.3048)
			(end -0.67945 0.3048)
			(stroke
				(width 0.1)
				(type default)
			)
			(layer "F.Fab")
		)
		(fp_line
			(start 0.120396 0.2794)
			(end -0.12065 0.2794)
			(stroke
				(width 0.1)
				(type default)
			)
			(layer "F.Fab")
		)
		(fp_line
			(start 0.120396 0.3048)
			(end 0.120396 0.2794)
			(stroke
				(width 0.1)
				(type default)
			)
			(layer "F.Fab")
		)
		(fp_line
			(start 0.12065 -0.3048)
			(end 0.67945 -0.3048)
			(stroke
				(width 0.1)
				(type default)
			)
			(layer "F.Fab")
		)
		(fp_line
			(start 0.12065 -0.2794)
			(end 0.12065 -0.3048)
			(stroke
				(width 0.1)
				(type default)
			)
			(layer "F.Fab")
		)
		(fp_line
			(start 0.67945 -0.3048)
			(end 0.67945 0.3048)
			(stroke
				(width 0.1)
				(type default)
			)
			(layer "F.Fab")
		)
		(fp_line
			(start 0.67945 0.3048)
			(end 0.120396 0.3048)
			(stroke
				(width 0.1)
				(type default)
			)
			(layer "F.Fab")
		)
		(pad "1" smd circle
			(at -0.40005 0)
			(size 0 0)
			(layers "F.Cu" "F.Mask" "F.Paste")
			(net "SPI_BMC_TPM_CLK_R")
		)
		(pad "2" smd circle
			(at 0.40005 0)
			(size 0 0)
			(layers "F.Cu" "F.Mask" "F.Paste")
			(net "SPI_BMC_TPM_CLK")
		)
	)
)
